(kicad_pcb
	(version 20260206)
	(generator "pcbnew")
	(generator_version "10.0")
	(general
		(thickness 1.6)
		(legacy_teardrops no)
	)
	(paper "A4")
	(title_block
		(title "Bryce Canyon_IOM_IOC_16318-2_OCP.brd")
		(comment 1 "Bryce Canyon / footprints 20-26 of 1605")
	)
	(layers
		(0 "F.Cu" signal "TOP")
		(4 "In1.Cu" signal "L2GND")
		(6 "In2.Cu" signal "L3")
		(8 "In3.Cu" signal "L4VCC")
		(10 "In4.Cu" signal "L5VCC")
		(12 "In5.Cu" signal "L6")
		(14 "In6.Cu" signal "L7GND")
		(2 "B.Cu" signal "BOTTOM")
		(9 "F.Adhes" user "F.Adhesive")
		(11 "B.Adhes" user "B.Adhesive")
		(13 "F.Paste" user "Package Geometry/Pastemask Top")
		(15 "B.Paste" user "Package Geometry/Pastemask Bottom")
		(5 "F.SilkS" user "Ref Des/Silkscreen Top")
		(7 "B.SilkS" user "Ref Des/Silkscreen Bottom")
		(1 "F.Mask" user "Board Geometry/Soldermask Top")
		(3 "B.Mask" user "Board Geometry/Soldermask Bottom")
		(17 "Dwgs.User" user "User.Drawings")
		(19 "Cmts.User" user "User.Comments")
		(21 "Eco1.User" user "User.Eco1")
		(23 "Eco2.User" user "User.Eco2")
		(25 "Edge.Cuts" user "Board Geometry/Outline")
		(27 "Margin" user)
		(31 "F.CrtYd" user "Package Geometry/Place Bound Top")
		(29 "B.CrtYd" user "Package Geometry/Place Bound Bottom")
		(35 "F.Fab" user "Ref Des/Assembly Top")
		(33 "B.Fab" user "Ref Des/Assembly Bottom")
	)
	(footprint ""
		(layer "F.Cu")
		(at 40.894 -164.084)
		(property "Reference" "R301"
			(at 0 0 0)
			(layer "F.SilkS")
			(hide yes)
			(effects
				(font
					(size 1.27 1.27)
				)
			)
		)
		(property "Value" "0R2J-2-GP"
			(at 0.064008 -3.993896 0)
			(unlocked yes)
			(layer "F.Fab")
			(hide yes)
			(effects
				(font
					(size 1.016 1.016)
					(thickness 0.1524)
				)
			)
		)
		(property "Device Type" "R402H16"
			(at 0.064008 -5.517896 0)
			(unlocked yes)
			(layer "F.Fab")
			(hide yes)
			(effects
				(font
					(size 1.016 1.016)
					(thickness 0.1524)
				)
			)
		)
		(duplicate_pad_numbers_are_jumpers no)
		(fp_line
			(start -0.508 -0.9398)
			(end -0.508 0.9398)
			(stroke
				(width 0.1524)
				(type default)
			)
			(layer "F.SilkS")
		)
		(fp_line
			(start 0.508 -0.9398)
			(end -0.508 -0.9398)
			(stroke
				(width 0.1524)
				(type default)
			)
			(layer "F.SilkS")
		)
		(fp_rect
			(start -0.508 0.9398)
			(end 0.508 -0.9398)
			(stroke
				(width 0)
				(type default)
			)
			(fill no)
			(layer "F.CrtYd")
		)
		(fp_rect
			(start -0.508 0.9398)
			(end 0.508 -0.9398)
			(stroke
				(width 0)
				(type default)
			)
			(fill no)
			(layer "F.Fab")
		)
		(pad "1" smd custom
			(at 0 -0.4445)
			(size 0.1397 0.1397)
			(layers "F.Cu" "F.Mask" "F.Paste")
			(net "UART_EXP_BMC_RX")
			(options
				(clearance outline)
				(anchor circle)
			)
			(primitives
				(gr_poly
					(pts
						(arc
							(start -0.1778 -0.2794)
							(mid -0.249642 -0.249642)
							(end -0.2794 -0.1778)
						)
						(arc
							(start -0.2794 0.1778)
							(mid -0.249642 0.249642)
							(end -0.1778 0.2794)
						)
						(arc
							(start 0.1778 0.2794)
							(mid 0.249642 0.249642)
							(end 0.2794 0.1778)
						)
						(arc
							(start 0.2794 -0.1778)
							(mid 0.249642 -0.249642)
							(end 0.1778 -0.2794)
						)
					)
					(width 0)
					(fill yes)
				)
			)
		)
		(pad "2" smd custom
			(at 0 0.4445)
			(size 0.1397 0.1397)
			(layers "F.Cu" "F.Mask" "F.Paste")
			(net "UART_EXP_BMC_RX_R")
			(options
				(clearance outline)
				(anchor circle)
			)
			(primitives
				(gr_poly
					(pts
						(arc
							(start -0.1778 -0.2794)
							(mid -0.249642 -0.249642)
							(end -0.2794 -0.1778)
						)
						(arc
							(start -0.2794 0.1778)
							(mid -0.249642 0.249642)
							(end -0.1778 0.2794)
						)
						(arc
							(start 0.1778 0.2794)
							(mid 0.249642 0.249642)
							(end 0.2794 0.1778)
						)
						(arc
							(start 0.2794 -0.1778)
							(mid 0.249642 -0.249642)
							(end 0.1778 -0.2794)
						)
					)
					(width 0)
					(fill yes)
				)
			)
		)
	)
	(footprint ""
		(layer "F.Cu")
		(at 135.62076 -17.88414 180)
		(property "Reference" "C139"
			(at 0 0 180)
			(layer "F.SilkS")
			(hide yes)
			(effects
				(font
					(size 1.27 1.27)
				)
			)
		)
		(property "Value" "SCD1U50V3KX-GP"
			(at 0 -2.8194 180)
			(unlocked yes)
			(layer "F.Fab")
			(hide yes)
			(effects
				(font
					(size 1.016 1.016)
					(thickness 0.1524)
				)
			)
		)
		(property "Device Type" "C603H36"
			(at 0 -4.3434 180)
			(unlocked yes)
			(layer "F.Fab")
			(hide yes)
			(effects
				(font
					(size 1.016 1.016)
					(thickness 0.1524)
				)
			)
		)
		(duplicate_pad_numbers_are_jumpers no)
		(fp_line
			(start 0.508 0)
			(end -0.508 0)
			(stroke
				(width 0.2032)
				(type default)
			)
			(layer "F.SilkS")
		)
		(fp_rect
			(start -0.5842 1.3335)
			(end 0.5842 -1.3335)
			(stroke
				(width 0)
				(type default)
			)
			(fill no)
			(layer "F.CrtYd")
		)
		(fp_rect
			(start -0.5842 1.3335)
			(end 0.5842 -1.3335)
			(stroke
				(width 0)
				(type default)
			)
			(fill no)
			(layer "F.Fab")
		)
		(pad "1" smd custom
			(at 0 -0.762 180)
			(size 0.2159 0.2159)
			(layers "F.Cu" "F.Mask" "F.Paste")
			(net "P12V_IOM")
			(options
				(clearance outline)
				(anchor circle)
			)
			(primitives
				(gr_poly
					(pts
						(arc
							(start -0.3302 -0.4318)
							(mid -0.402042 -0.402042)
							(end -0.4318 -0.3302)
						)
						(arc
							(start -0.4318 0.3302)
							(mid -0.402042 0.402042)
							(end -0.3302 0.4318)
						)
						(arc
							(start 0.3302 0.4318)
							(mid 0.402042 0.402042)
							(end 0.4318 0.3302)
						)
						(arc
							(start 0.4318 -0.3302)
							(mid 0.402042 -0.402042)
							(end 0.3302 -0.4318)
						)
					)
					(width 0)
					(fill yes)
				)
			)
		)
		(pad "2" smd custom
			(at 0 0.762 180)
			(size 0.2159 0.2159)
			(layers "F.Cu" "F.Mask" "F.Paste")
			(net "GND")
			(options
				(clearance outline)
				(anchor circle)
			)
			(primitives
				(gr_poly
					(pts
						(arc
							(start -0.3302 -0.4318)
							(mid -0.402042 -0.402042)
							(end -0.4318 -0.3302)
						)
						(arc
							(start -0.4318 0.3302)
							(mid -0.402042 0.402042)
							(end -0.3302 0.4318)
						)
						(arc
							(start 0.3302 0.4318)
							(mid 0.402042 0.402042)
							(end 0.4318 0.3302)
						)
						(arc
							(start 0.4318 -0.3302)
							(mid 0.402042 -0.402042)
							(end 0.3302 -0.4318)
						)
					)
					(width 0)
					(fill yes)
				)
			)
		)
	)
	(footprint ""
		(layer "F.Cu")
		(at 23.78456 -14.69644)
		(property "Reference" "D2"
			(at 0 0 0)
			(layer "F.SilkS")
			(hide yes)
			(effects
				(font
					(size 1.27 1.27)
				)
			)
		)
		(property "Value" "PESD5V0X1UAB-GP"
			(at 0 -4.690618 0)
			(unlocked yes)
			(layer "F.Fab")
			(hide yes)
			(effects
				(font
					(size 1.016 1.016)
					(thickness 0.1524)
				)
			)
		)
		(property "Device Type" "SOD523AKH26"
			(at 0 -6.214618 0)
			(unlocked yes)
			(layer "F.Fab")
			(hide yes)
			(effects
				(font
					(size 1.016 1.016)
					(thickness 0.1524)
				)
			)
		)
		(duplicate_pad_numbers_are_jumpers no)
		(fp_line
			(start -0.5334 -1.4478)
			(end 0.5334 -1.4478)
			(stroke
				(width 0.1524)
				(type default)
			)
			(layer "F.SilkS")
		)
		(fp_line
			(start -0.5334 1.524)
			(end -0.5334 -1.4478)
			(stroke
				(width 0.1524)
				(type default)
			)
			(layer "F.SilkS")
		)
		(fp_line
			(start 0.4064 1.651)
			(end -0.4064 1.651)
			(stroke
				(width 0.4064)
				(type default)
			)
			(layer "F.SilkS")
		)
		(fp_line
			(start 0.5334 -1.4478)
			(end 0.5334 1.524)
			(stroke
				(width 0.1524)
				(type default)
			)
			(layer "F.SilkS")
		)
		(fp_line
			(start 0.5334 1.524)
			(end -0.5334 1.524)
			(stroke
				(width 0.1524)
				(type default)
			)
			(layer "F.SilkS")
		)
		(fp_rect
			(start -0.6096 1.8542)
			(end 0.6096 -1.524)
			(stroke
				(width 0)
				(type default)
			)
			(fill no)
			(layer "F.CrtYd")
		)
		(fp_poly
			(pts
				(xy -0.6096 -1.524) (xy 0.6096 -1.524) (xy 0.6096 1.8542) (xy -0.6096 1.8542)
			)
			(stroke
				(width 0)
				(type default)
			)
			(fill no)
			(layer "F.Fab")
		)
		(pad "A" smd rect
			(at 0 -0.762)
			(size 0.5588 1.016)
			(layers "F.Cu" "F.Mask" "F.Paste")
			(net "GND")
		)
		(pad "K" smd rect
			(at 0 0.762)
			(size 0.5588 1.016)
			(layers "F.Cu" "F.Mask" "F.Paste")
			(net "FP_PWR_BTN_N")
		)
	)
	(footprint ""
		(layer "F.Cu")
		(at 73.4187 -136.398 180)
		(property "Reference" "R102"
			(at 0 0 180)
			(layer "F.SilkS")
			(hide yes)
			(effects
				(font
					(size 1.27 1.27)
				)
			)
		)
		(property "Value" "0R2J-2-GP"
			(at 0.064008 -3.993896 180)
			(unlocked yes)
			(layer "F.Fab")
			(hide yes)
			(effects
				(font
					(size 1.016 1.016)
					(thickness 0.1524)
				)
			)
		)
		(property "Device Type" "R402H16"
			(at 0.064008 -5.517896 180)
			(unlocked yes)
			(layer "F.Fab")
			(hide yes)
			(effects
				(font
					(size 1.016 1.016)
					(thickness 0.1524)
				)
			)
		)
		(duplicate_pad_numbers_are_jumpers no)
		(fp_line
			(start 0.508 -0.9398)
			(end -0.508 -0.9398)
			(stroke
				(width 0.1524)
				(type default)
			)
			(layer "F.SilkS")
		)
		(fp_line
			(start -0.508 -0.9398)
			(end -0.508 0.9398)
			(stroke
				(width 0.1524)
				(type default)
			)
			(layer "F.SilkS")
		)
		(fp_rect
			(start -0.508 0.9398)
			(end 0.508 -0.9398)
			(stroke
				(width 0)
				(type default)
			)
			(fill no)
			(layer "F.CrtYd")
		)
		(fp_rect
			(start -0.508 0.9398)
			(end 0.508 -0.9398)
			(stroke
				(width 0)
				(type default)
			)
			(fill no)
			(layer "F.Fab")
		)
		(pad "1" smd custom
			(at 0 -0.4445 180)
			(size 0.1397 0.1397)
			(layers "F.Cu" "F.Mask" "F.Paste")
			(net "BMC_UART_SEL_IN")
			(options
				(clearance outline)
				(anchor circle)
			)
			(primitives
				(gr_poly
					(pts
						(arc
							(start -0.1778 -0.2794)
							(mid -0.249642 -0.249642)
							(end -0.2794 -0.1778)
						)
						(arc
							(start -0.2794 0.1778)
							(mid -0.249642 0.249642)
							(end -0.1778 0.2794)
						)
						(arc
							(start 0.1778 0.2794)
							(mid 0.249642 0.249642)
							(end 0.2794 0.1778)
						)
						(arc
							(start 0.2794 -0.1778)
							(mid 0.249642 -0.249642)
							(end 0.1778 -0.2794)
						)
					)
					(width 0)
					(fill yes)
				)
			)
		)
		(pad "2" smd custom
			(at 0 0.4445 180)
			(size 0.1397 0.1397)
			(layers "F.Cu" "F.Mask" "F.Paste")
			(net "DEBUG_HDR_UART_SEL")
			(options
				(clearance outline)
				(anchor circle)
			)
			(primitives
				(gr_poly
					(pts
						(arc
							(start -0.1778 -0.2794)
							(mid -0.249642 -0.249642)
							(end -0.2794 -0.1778)
						)
						(arc
							(start -0.2794 0.1778)
							(mid -0.249642 0.249642)
							(end -0.1778 0.2794)
						)
						(arc
							(start 0.1778 0.2794)
							(mid 0.249642 0.249642)
							(end 0.2794 0.1778)
						)
						(arc
							(start 0.2794 -0.1778)
							(mid 0.249642 -0.249642)
							(end 0.1778 -0.2794)
						)
					)
					(width 0)
					(fill yes)
				)
			)
		)
	)
	(footprint ""
		(layer "F.Cu")
		(at 31.4706 -165.0238)
		(property "Reference" "R703"
			(at 0 0 0)
			(layer "F.SilkS")
			(hide yes)
			(effects
				(font
					(size 1.27 1.27)
				)
			)
		)
		(property "Value" "4K7R2F-GP"
			(at 0.064008 -3.993896 0)
			(unlocked yes)
			(layer "F.Fab")
			(hide yes)
			(effects
				(font
					(size 1.016 1.016)
					(thickness 0.1524)
				)
			)
		)
		(property "Device Type" "R402H16"
			(at 0.064008 -5.517896 0)
			(unlocked yes)
			(layer "F.Fab")
			(hide yes)
			(effects
				(font
					(size 1.016 1.016)
					(thickness 0.1524)
				)
			)
		)
		(duplicate_pad_numbers_are_jumpers no)
		(fp_line
			(start -0.508 -0.9398)
			(end -0.508 0.9398)
			(stroke
				(width 0.1524)
				(type default)
			)
			(layer "F.SilkS")
		)
		(fp_line
			(start 0.508 -0.9398)
			(end -0.508 -0.9398)
			(stroke
				(width 0.1524)
				(type default)
			)
			(layer "F.SilkS")
		)
		(fp_rect
			(start -0.508 0.9398)
			(end 0.508 -0.9398)
			(stroke
				(width 0)
				(type default)
			)
			(fill no)
			(layer "F.CrtYd")
		)
		(fp_rect
			(start -0.508 0.9398)
			(end 0.508 -0.9398)
			(stroke
				(width 0)
				(type default)
			)
			(fill no)
			(layer "F.Fab")
		)
		(pad "1" smd custom
			(at 0 -0.4445)
			(size 0.1397 0.1397)
			(layers "F.Cu" "F.Mask" "F.Paste")
			(net "GND")
			(options
				(clearance outline)
				(anchor circle)
			)
			(primitives
				(gr_poly
					(pts
						(arc
							(start -0.1778 -0.2794)
							(mid -0.249642 -0.249642)
							(end -0.2794 -0.1778)
						)
						(arc
							(start -0.2794 0.1778)
							(mid -0.249642 0.249642)
							(end -0.1778 0.2794)
						)
						(arc
							(start 0.1778 0.2794)
							(mid 0.249642 0.249642)
							(end 0.2794 0.1778)
						)
						(arc
							(start 0.2794 -0.1778)
							(mid 0.249642 -0.249642)
							(end 0.1778 -0.2794)
						)
					)
					(width 0)
					(fill yes)
				)
			)
		)
		(pad "2" smd custom
			(at 0 0.4445)
			(size 0.1397 0.1397)
			(layers "F.Cu" "F.Mask" "F.Paste")
			(net "IOM_TYPE1")
			(options
				(clearance outline)
				(anchor circle)
			)
			(primitives
				(gr_poly
					(pts
						(arc
							(start -0.1778 -0.2794)
							(mid -0.249642 -0.249642)
							(end -0.2794 -0.1778)
						)
						(arc
							(start -0.2794 0.1778)
							(mid -0.249642 0.249642)
							(end -0.1778 0.2794)
						)
						(arc
							(start 0.1778 0.2794)
							(mid 0.249642 0.249642)
							(end 0.2794 0.1778)
						)
						(arc
							(start 0.2794 -0.1778)
							(mid 0.249642 -0.249642)
							(end 0.1778 -0.2794)
						)
					)
					(width 0)
					(fill yes)
				)
			)
		)
	)
	(footprint ""
		(layer "F.Cu")
		(at 57.3024 -131.33832)
		(property "Reference" "R278"
			(at 0 0 0)
			(layer "F.SilkS")
			(hide yes)
			(effects
				(font
					(size 1.27 1.27)
				)
			)
		)
		(property "Value" "0R2J-2-GP"
			(at 0.064008 -3.993896 0)
			(unlocked yes)
			(layer "F.Fab")
			(hide yes)
			(effects
				(font
					(size 1.016 1.016)
					(thickness 0.1524)
				)
			)
		)
		(property "Device Type" "R402H16"
			(at 0.064008 -5.517896 0)
			(unlocked yes)
			(layer "F.Fab")
			(hide yes)
			(effects
				(font
					(size 1.016 1.016)
					(thickness 0.1524)
				)
			)
		)
		(duplicate_pad_numbers_are_jumpers no)
		(fp_line
			(start -0.508 -0.9398)
			(end -0.508 0.9398)
			(stroke
				(width 0.1524)
				(type default)
			)
			(layer "F.SilkS")
		)
		(fp_line
			(start 0.508 -0.9398)
			(end -0.508 -0.9398)
			(stroke
				(width 0.1524)
				(type default)
			)
			(layer "F.SilkS")
		)
		(fp_rect
			(start -0.508 0.9398)
			(end 0.508 -0.9398)
			(stroke
				(width 0)
				(type default)
			)
			(fill no)
			(layer "F.CrtYd")
		)
		(fp_rect
			(start -0.508 0.9398)
			(end 0.508 -0.9398)
			(stroke
				(width 0)
				(type default)
			)
			(fill no)
			(layer "F.Fab")
		)
		(pad "1" smd custom
			(at 0 -0.4445)
			(size 0.1397 0.1397)
			(layers "F.Cu" "F.Mask" "F.Paste")
			(net "RSTBTN_OUT_N_R")
			(options
				(clearance outline)
				(anchor circle)
			)
			(primitives
				(gr_poly
					(pts
						(arc
							(start -0.1778 -0.2794)
							(mid -0.249642 -0.249642)
							(end -0.2794 -0.1778)
						)
						(arc
							(start -0.2794 0.1778)
							(mid -0.249642 0.249642)
							(end -0.1778 0.2794)
						)
						(arc
							(start 0.1778 0.2794)
							(mid 0.249642 0.249642)
							(end 0.2794 0.1778)
						)
						(arc
							(start 0.2794 -0.1778)
							(mid 0.249642 -0.249642)
							(end 0.1778 -0.2794)
						)
					)
					(width 0)
					(fill yes)
				)
			)
		)
		(pad "2" smd custom
			(at 0 0.4445)
			(size 0.1397 0.1397)
			(layers "F.Cu" "F.Mask" "F.Paste")
			(net "RSTBTN_OUT_N")
			(options
				(clearance outline)
				(anchor circle)
			)
			(primitives
				(gr_poly
					(pts
						(arc
							(start -0.1778 -0.2794)
							(mid -0.249642 -0.249642)
							(end -0.2794 -0.1778)
						)
						(arc
							(start -0.2794 0.1778)
							(mid -0.249642 0.249642)
							(end -0.1778 0.2794)
						)
						(arc
							(start 0.1778 0.2794)
							(mid 0.249642 0.249642)
							(end 0.2794 0.1778)
						)
						(arc
							(start 0.2794 -0.1778)
							(mid 0.249642 -0.249642)
							(end 0.1778 -0.2794)
						)
					)
					(width 0)
					(fill yes)
				)
			)
		)
	)
	(footprint ""
		(layer "F.Cu")
		(at 31.5976 -161.6456 90)
		(property "Reference" "R700"
			(at 0 0 90)
			(layer "F.SilkS")
			(hide yes)
			(effects
				(font
					(size 1.27 1.27)
				)
			)
		)
		(property "Value" "4K7R2F-GP"
			(at 0.064008 -3.993896 90)
			(unlocked yes)
			(layer "F.Fab")
			(hide yes)
			(effects
				(font
					(size 1.016 1.016)
					(thickness 0.1524)
				)
			)
		)
		(property "Device Type" "R402H16"
			(at 0.064008 -5.517896 90)
			(unlocked yes)
			(layer "F.Fab")
			(hide yes)
			(effects
				(font
					(size 1.016 1.016)
					(thickness 0.1524)
				)
			)
		)
		(duplicate_pad_numbers_are_jumpers no)
		(fp_line
			(start 0.508 -0.9398)
			(end -0.508 -0.9398)
			(stroke
				(width 0.1524)
				(type default)
			)
			(layer "F.SilkS")
		)
		(fp_line
			(start -0.508 -0.9398)
			(end -0.508 0.9398)
			(stroke
				(width 0.1524)
				(type default)
			)
			(layer "F.SilkS")
		)
		(fp_rect
			(start -0.508 0.9398)
			(end 0.508 -0.9398)
			(stroke
				(width 0)
				(type default)
			)
			(fill no)
			(layer "F.CrtYd")
		)
		(fp_rect
			(start -0.508 0.9398)
			(end 0.508 -0.9398)
			(stroke
				(width 0)
				(type default)
			)
			(fill no)
			(layer "F.Fab")
		)
		(pad "1" smd custom
			(at 0 -0.4445 90)
			(size 0.1397 0.1397)
			(layers "F.Cu" "F.Mask" "F.Paste")
			(net "P3V3_STBY")
			(options
				(clearance outline)
				(anchor circle)
			)
			(primitives
				(gr_poly
					(pts
						(arc
							(start -0.1778 -0.2794)
							(mid -0.249642 -0.249642)
							(end -0.2794 -0.1778)
						)
						(arc
							(start -0.2794 0.1778)
							(mid -0.249642 0.249642)
							(end -0.1778 0.2794)
						)
						(arc
							(start 0.1778 0.2794)
							(mid 0.249642 0.249642)
							(end 0.2794 0.1778)
						)
						(arc
							(start 0.2794 -0.1778)
							(mid 0.249642 -0.249642)
							(end 0.1778 -0.2794)
						)
					)
					(width 0)
					(fill yes)
				)
			)
		)
		(pad "2" smd custom
			(at 0 0.4445 90)
			(size 0.1397 0.1397)
			(layers "F.Cu" "F.Mask" "F.Paste")
			(net "IOM_TYPE3")
			(options
				(clearance outline)
				(anchor circle)
			)
			(primitives
				(gr_poly
					(pts
						(arc
							(start -0.1778 -0.2794)
							(mid -0.249642 -0.249642)
							(end -0.2794 -0.1778)
						)
						(arc
							(start -0.2794 0.1778)
							(mid -0.249642 0.249642)
							(end -0.1778 0.2794)
						)
						(arc
							(start 0.1778 0.2794)
							(mid 0.249642 0.249642)
							(end 0.2794 0.1778)
						)
						(arc
							(start 0.2794 -0.1778)
							(mid 0.249642 -0.249642)
							(end 0.1778 -0.2794)
						)
					)
					(width 0)
					(fill yes)
				)
			)
		)
	)
)
